(kicad_pcb
	(version 20240108)
	(generator "pcbnew")
	(generator_version "8.0")
	(general
		(thickness 1.62)
		(legacy_teardrops no)
	)
	(paper "A4")
	(title_block
		(title "Jetson Orin Baseboard")
		(date "2025-03-12")
		(rev "1.3.4")
		(company "Antmicro Ltd")
		(comment 1 "www.antmicro.com")
		(comment 9 "footprints 318-320 of 677")
	)
	(layers
		(0 "F.Cu" signal)
		(1 "In1.Cu" signal)
		(2 "In2.Cu" signal)
		(3 "In3.Cu" signal)
		(4 "In4.Cu" jumper)
		(5 "In5.Cu" signal)
		(6 "In6.Cu" signal)
		(31 "B.Cu" signal)
		(32 "B.Adhes" user "B.Adhesive")
		(33 "F.Adhes" user "F.Adhesive")
		(34 "B.Paste" user)
		(35 "F.Paste" user)
		(36 "B.SilkS" user "B.Silkscreen")
		(37 "F.SilkS" user "F.Silkscreen")
		(38 "B.Mask" user)
		(39 "F.Mask" user)
		(40 "Dwgs.User" user "User.Drawings")
		(41 "Cmts.User" user "User.Comments")
		(42 "Eco1.User" user "User.Eco1")
		(43 "Eco2.User" user "User.Eco2")
		(44 "Edge.Cuts" user)
		(45 "Margin" user)
		(46 "B.CrtYd" user "B.Courtyard")
		(47 "F.CrtYd" user "F.Courtyard")
		(48 "B.Fab" user)
		(49 "F.Fab" user)
	)
	(footprint "antmicro-footprints:WSON-6-1EP_2x2mm_P0.65mm"
		(layer "B.Cu")
		(at 47.175 123.945 -90)
		(property "Reference" "U8"
			(at 2.315 -1.315 180)
			(layer "B.SilkS")
			(effects
				(font
					(size 0.7 0.7)
					(thickness 0.15)
				)
				(justify left bottom mirror)
			)
		)
		(property "Value" "NCP730BMT330_WSON"
			(at 0 -2.2 90)
			(layer "B.Fab")
			(effects
				(font
					(size 0.7 0.7)
					(thickness 0.15)
				)
				(justify left bottom mirror)
			)
		)
		(property "Footprint" "antmicro-footprints:WSON-6-1EP_2x2mm_P0.65mm"
			(at 0 0 -90)
			(layer "F.Fab")
			(hide yes)
			(effects
				(font
					(size 1.27 1.27)
					(thickness 0.15)
				)
			)
		)
		(property "Datasheet" "https://www.onsemi.com/download/data-sheet/pdf/ncp730-d.pdf"
			(at 0 0 -90)
			(layer "F.Fab")
			(hide yes)
			(effects
				(font
					(size 1.27 1.27)
					(thickness 0.15)
				)
			)
		)
		(property "Author" "Antmicro"
			(at -76.77 171.12 0)
			(layer "B.Fab")
			(hide yes)
			(effects
				(font
					(size 1 1)
					(thickness 0.15)
				)
				(justify mirror)
			)
		)
		(property "License" "Apache-2.0"
			(at -76.77 171.12 0)
			(layer "B.Fab")
			(hide yes)
			(effects
				(font
					(size 1 1)
					(thickness 0.15)
				)
				(justify mirror)
			)
		)
		(property "MPN" "NCP730BMT330TBG"
			(at -76.77 171.12 0)
			(layer "B.Fab")
			(hide yes)
			(effects
				(font
					(size 1 1)
					(thickness 0.15)
				)
				(justify mirror)
			)
		)
		(property "Manufacturer" "ON Semiconductor"
			(at -76.77 171.12 0)
			(layer "B.Fab")
			(hide yes)
			(effects
				(font
					(size 1 1)
					(thickness 0.15)
				)
				(justify mirror)
			)
		)
		(sheetname "USB Debug, DP")
		(sheetfile "usb.kicad_sch")
		(attr smd)
		(fp_line
			(start -1.05 1)
			(end 1 1)
			(stroke
				(width 0.12)
				(type solid)
			)
			(layer "B.SilkS")
		)
		(fp_line
			(start 1 -1)
			(end -1 -1)
			(stroke
				(width 0.12)
				(type solid)
			)
			(layer "B.SilkS")
		)
		(fp_circle
			(center -1.275 1.075)
			(end -1.224 1.075)
			(stroke
				(width 0.15)
				(type solid)
			)
			(fill solid)
			(layer "B.SilkS")
		)
		(fp_rect
			(start -1.45 1.25)
			(end 1.45 -1.25)
			(stroke
				(width 0.05)
				(type solid)
			)
			(fill none)
			(layer "B.CrtYd")
		)
		(fp_text user "Author: Antmicro"
			(at -1.01 -5.2 90)
			(layer "B.Fab")
			(hide yes)
			(effects
				(font
					(size 0.7 0.7)
					(thickness 0.15)
				)
				(justify left bottom mirror)
			)
		)
		(fp_text user "License: Apache-2.0"
			(at -1.01 -6.4 90)
			(layer "B.Fab")
			(hide yes)
			(effects
				(font
					(size 0.7 0.7)
					(thickness 0.15)
				)
				(justify left bottom mirror)
			)
		)
		(fp_text user "${REFERENCE}"
			(at -1.01 -3.999 90)
			(layer "B.Fab")
			(hide yes)
			(effects
				(font
					(size 0.7 0.7)
					(thickness 0.15)
				)
				(justify left bottom mirror)
			)
		)
		(pad "1" smd roundrect
			(at -0.975 0.652 270)
			(size 0.45 0.4)
			(layers "B.Cu" "B.Paste" "B.Mask")
			(roundrect_rratio 0.25)
			(net 185 "/USB Debug, DP/FTDI_3V3")
			(pinfunction "V_{OUT}")
			(pintype "power_out")
		)
		(pad "2" smd roundrect
			(at -0.975 0 270)
			(size 0.45 0.4)
			(layers "B.Cu" "B.Paste" "B.Mask")
			(roundrect_rratio 0.25)
			(net 702 "unconnected-(U8-NC-Pad2)")
			(pinfunction "NC")
			(pintype "no_connect")
		)
		(pad "3" smd roundrect
			(at -0.975 -0.65 270)
			(size 0.45 0.4)
			(layers "B.Cu" "B.Paste" "B.Mask")
			(roundrect_rratio 0.25)
			(net 1 "GND")
			(pinfunction "GND")
			(pintype "power_in")
		)
		(pad "4" smd roundrect
			(at 0.973 -0.65 270)
			(size 0.45 0.4)
			(layers "B.Cu" "B.Paste" "B.Mask")
			(roundrect_rratio 0.25)
			(net 196 "/USB Debug, DP/USBC3_VBUS")
			(pinfunction "EN")
			(pintype "input")
		)
		(pad "5" smd roundrect
			(at 0.973 0 270)
			(size 0.45 0.4)
			(layers "B.Cu" "B.Paste" "B.Mask")
			(roundrect_rratio 0.25)
			(net 1 "GND")
			(pinfunction "PG")
			(pintype "open_collector")
		)
		(pad "6" smd roundrect
			(at 0.973 0.652 270)
			(size 0.45 0.4)
			(layers "B.Cu" "B.Paste" "B.Mask")
			(roundrect_rratio 0.25)
			(net 196 "/USB Debug, DP/USBC3_VBUS")
			(pinfunction "V_{IN}")
			(pintype "power_in")
		)
		(pad "7" smd roundrect
			(at 0 0 270)
			(size 1.12 1.72)
			(layers "B.Cu" "B.Paste" "B.Mask")
			(roundrect_rratio 0.1)
			(net 1 "GND")
			(pinfunction "GND")
			(pintype "passive")
		)
	)
	(footprint "antmicro-footprints:Spacer_Drill3.7mm_H6.5mm_9774065151R"
		(locked yes)
		(layer "B.Cu")
		(at 144.75 123.75 180)
		(descr "Spacer M=3 h=6.5mm fi=5.1mm")
		(property "Reference" "H3"
			(at 1.05 -3.85 0)
			(layer "B.SilkS")
			(effects
				(font
					(size 0.7 0.7)
					(thickness 0.15)
				)
				(justify left bottom mirror)
			)
		)
		(property "Value" "Spacer_Drill3.7mm_H6.5mm_9774065151R"
			(at 0 -4 0)
			(layer "B.Fab")
			(effects
				(font
					(size 0.7 0.7)
					(thickness 0.15)
				)
				(justify left bottom mirror)
			)
		)
		(property "Footprint" "antmicro-footprints:Spacer_Drill3.7mm_H6.5mm_9774065151R"
			(at 0 0 180)
			(layer "F.Fab")
			(hide yes)
			(effects
				(font
					(size 1.27 1.27)
					(thickness 0.15)
				)
			)
		)
		(property "Datasheet" "https://www.we-online.com/components/products/datasheet/9774065151R.pdf"
			(at 0 0 180)
			(layer "F.Fab")
			(hide yes)
			(effects
				(font
					(size 1.27 1.27)
					(thickness 0.15)
				)
			)
		)
		(property "Author" "Antmicro"
			(at 289.5 247.5 0)
			(layer "B.Fab")
			(hide yes)
			(effects
				(font
					(size 1 1)
					(thickness 0.15)
				)
				(justify mirror)
			)
		)
		(property "License" "Apache-2.0"
			(at 289.5 247.5 0)
			(layer "B.Fab")
			(hide yes)
			(effects
				(font
					(size 1 1)
					(thickness 0.15)
				)
				(justify mirror)
			)
		)
		(property "MPN" "9774065151R"
			(at 289.5 247.5 0)
			(layer "B.Fab")
			(hide yes)
			(effects
				(font
					(size 1 1)
					(thickness 0.15)
				)
				(justify mirror)
			)
		)
		(property "Manufacturer" "Würth Elektronik"
			(at 289.5 247.5 0)
			(layer "B.Fab")
			(hide yes)
			(effects
				(font
					(size 1 1)
					(thickness 0.15)
				)
				(justify mirror)
			)
		)
		(sheetname "Root")
		(sheetfile "jetson-orin-baseboard.kicad_sch")
		(solder_paste_ratio -1)
		(attr smd)
		(fp_circle
			(center 0 0)
			(end 3.05 0)
			(stroke
				(width 0.05)
				(type solid)
			)
			(fill none)
			(layer "B.CrtYd")
		)
		(fp_circle
			(center 0 0)
			(end 2.6 0)
			(stroke
				(width 0.15)
				(type solid)
			)
			(fill none)
			(layer "B.Fab")
		)
		(fp_text user "License: Apache-2.0"
			(at -9.6 -8.9 0)
			(layer "B.Fab")
			(hide yes)
			(effects
				(font
					(size 0.7 0.7)
					(thickness 0.15)
				)
				(justify left bottom mirror)
			)
		)
		(fp_text user "Author: Antmicro"
			(at -9.6 -7.7 0)
			(layer "B.Fab")
			(hide yes)
			(effects
				(font
					(size 0.7 0.7)
					(thickness 0.15)
				)
				(justify left bottom mirror)
			)
		)
		(fp_text user "${REFERENCE}"
			(at -9.6 -6.5 0)
			(layer "B.Fab")
			(hide yes)
			(effects
				(font
					(size 0.7 0.7)
					(thickness 0.15)
				)
				(justify left bottom mirror)
			)
		)
		(pad "" smd custom
			(at -1.7 -1.7 90)
			(size 0.62 0.62)
			(layers "B.Paste")
			(thermal_bridge_angle 90)
			(options
				(clearance outline)
				(anchor circle)
			)
			(primitives
				(gr_arc
					(start 1.266786 0.24747)
					(mid 0.285453 -0.29439)
					(end -0.250195 -1.279127)
					(width 0.2)
				)
				(gr_arc
					(start 1.259603 0.339191)
					(mid 0.218448 -0.232561)
					(end -0.34334 -1.279127)
					(width 0.2)
				)
				(gr_arc
					(start 1.255279 0.431435)
					(mid 0.152481 -0.169693)
					(end -0.436309 -1.279127)
					(width 0.2)
				)
				(gr_arc
					(start 1.253811 0.524161)
					(mid 0.087542 -0.105784)
					(end -0.529126 -1.279127)
					(width 0.2)
				)
				(gr_arc
					(start 1.275473 0.621136)
					(mid 0.0309 -0.033527)
					(end -0.621807 -1.279127)
					(width 0.2)
				)
				(gr_arc
					(start 1.263664 0.711602)
					(mid -0.037759 0.026651)
					(end -0.71437 -1.279127)
					(width 0.2)
				)
				(gr_arc
					(start 1.253435 0.802342)
					(mid -0.105837 0.087395)
					(end -0.806826 -1.279127)
					(width 0.2)
				)
				(gr_arc
					(start 1.267475 0.897258)
					(mid -0.165236 0.156885)
					(end -0.899187 -1.279127)
					(width 0.2)
				)
				(gr_arc
					(start 1.270645 0.990112)
					(mid -0.228522 0.222449)
					(end -0.991463 -1.279127)
					(width 0.2)
				)
				(gr_arc
					(start 1.266278 1.081674)
					(mid -0.294507 0.285313)
					(end -1.083663 -1.279127)
					(width 0.2)
				)
				(gr_line
					(start 1.279127 1.083663)
					(end 1.279127 0.250195)
					(width 0.2)
				)
				(gr_line
					(start -1.083663 -1.279127)
					(end -0.250195 -1.279127)
					(width 0.2)
				)
			)
		)
		(pad "" smd custom
			(at -1.7 1.7 180)
			(size 0.62 0.62)
			(layers "B.Paste")
			(thermal_bridge_angle 90)
			(options
				(clearance outline)
				(anchor circle)
			)
			(primitives
				(gr_arc
					(start 1.266786 0.24747)
					(mid 0.285453 -0.29439)
					(end -0.250195 -1.279127)
					(width 0.2)
				)
				(gr_arc
					(start 1.259603 0.339191)
					(mid 0.218448 -0.232561)
					(end -0.34334 -1.279127)
					(width 0.2)
				)
				(gr_arc
					(start 1.255279 0.431435)
					(mid 0.152481 -0.169693)
					(end -0.436309 -1.279127)
					(width 0.2)
				)
				(gr_arc
					(start 1.253811 0.524161)
					(mid 0.087542 -0.105784)
					(end -0.529126 -1.279127)
					(width 0.2)
				)
				(gr_arc
					(start 1.275473 0.621136)
					(mid 0.0309 -0.033527)
					(end -0.621807 -1.279127)
					(width 0.2)
				)
				(gr_arc
					(start 1.263664 0.711602)
					(mid -0.037759 0.026651)
					(end -0.71437 -1.279127)
					(width 0.2)
				)
				(gr_arc
					(start 1.253435 0.802342)
					(mid -0.105837 0.087395)
					(end -0.806826 -1.279127)
					(width 0.2)
				)
				(gr_arc
					(start 1.267475 0.897258)
					(mid -0.165236 0.156885)
					(end -0.899187 -1.279127)
					(width 0.2)
				)
				(gr_arc
					(start 1.270645 0.990112)
					(mid -0.228522 0.222449)
					(end -0.991463 -1.279127)
					(width 0.2)
				)
				(gr_arc
					(start 1.266278 1.081674)
					(mid -0.294507 0.285313)
					(end -1.083663 -1.279127)
					(width 0.2)
				)
				(gr_line
					(start 1.279127 1.083663)
					(end 1.279127 0.250195)
					(width 0.2)
				)
				(gr_line
					(start -1.083663 -1.279127)
					(end -0.250195 -1.279127)
					(width 0.2)
				)
			)
		)
		(pad "" smd custom
			(at 1.7 -1.7)
			(size 0.62 0.62)
			(layers "B.Paste")
			(thermal_bridge_angle 90)
			(options
				(clearance outline)
				(anchor circle)
			)
			(primitives
				(gr_arc
					(start 1.266786 0.24747)
					(mid 0.285453 -0.29439)
					(end -0.250195 -1.279127)
					(width 0.2)
				)
				(gr_arc
					(start 1.259603 0.339191)
					(mid 0.218448 -0.232561)
					(end -0.34334 -1.279127)
					(width 0.2)
				)
				(gr_arc
					(start 1.255279 0.431435)
					(mid 0.152481 -0.169693)
					(end -0.436309 -1.279127)
					(width 0.2)
				)
				(gr_arc
					(start 1.253811 0.524161)
					(mid 0.087542 -0.105784)
					(end -0.529126 -1.279127)
					(width 0.2)
				)
				(gr_arc
					(start 1.275473 0.621136)
					(mid 0.0309 -0.033527)
					(end -0.621807 -1.279127)
					(width 0.2)
				)
				(gr_arc
					(start 1.263664 0.711602)
					(mid -0.037759 0.026651)
					(end -0.71437 -1.279127)
					(width 0.2)
				)
				(gr_arc
					(start 1.253435 0.802342)
					(mid -0.105837 0.087395)
					(end -0.806826 -1.279127)
					(width 0.2)
				)
				(gr_arc
					(start 1.267475 0.897258)
					(mid -0.165236 0.156885)
					(end -0.899187 -1.279127)
					(width 0.2)
				)
				(gr_arc
					(start 1.270645 0.990112)
					(mid -0.228522 0.222449)
					(end -0.991463 -1.279127)
					(width 0.2)
				)
				(gr_arc
					(start 1.266278 1.081674)
					(mid -0.294507 0.285313)
					(end -1.083663 -1.279127)
					(width 0.2)
				)
				(gr_line
					(start 1.279127 1.083663)
					(end 1.279127 0.250195)
					(width 0.2)
				)
				(gr_line
					(start -1.083663 -1.279127)
					(end -0.250195 -1.279127)
					(width 0.2)
				)
			)
		)
		(pad "" smd custom
			(at 1.7 1.7 270)
			(size 0.62 0.62)
			(layers "B.Paste")
			(thermal_bridge_angle 90)
			(options
				(clearance outline)
				(anchor circle)
			)
			(primitives
				(gr_arc
					(start 1.266786 0.24747)
					(mid 0.285453 -0.29439)
					(end -0.250195 -1.279127)
					(width 0.2)
				)
				(gr_arc
					(start 1.259603 0.339191)
					(mid 0.218448 -0.232561)
					(end -0.34334 -1.279127)
					(width 0.2)
				)
				(gr_arc
					(start 1.255279 0.431435)
					(mid 0.152481 -0.169693)
					(end -0.436309 -1.279127)
					(width 0.2)
				)
				(gr_arc
					(start 1.253811 0.524161)
					(mid 0.087542 -0.105784)
					(end -0.529126 -1.279127)
					(width 0.2)
				)
				(gr_arc
					(start 1.275473 0.621136)
					(mid 0.0309 -0.033527)
					(end -0.621807 -1.279127)
					(width 0.2)
				)
				(gr_arc
					(start 1.263664 0.711602)
					(mid -0.037759 0.026651)
					(end -0.71437 -1.279127)
					(width 0.2)
				)
				(gr_arc
					(start 1.253435 0.802342)
					(mid -0.105837 0.087395)
					(end -0.806826 -1.279127)
					(width 0.2)
				)
				(gr_arc
					(start 1.267475 0.897258)
					(mid -0.165236 0.156885)
					(end -0.899187 -1.279127)
					(width 0.2)
				)
				(gr_arc
					(start 1.270645 0.990112)
					(mid -0.228522 0.222449)
					(end -0.991463 -1.279127)
					(width 0.2)
				)
				(gr_arc
					(start 1.266278 1.081674)
					(mid -0.294507 0.285313)
					(end -1.083663 -1.279127)
					(width 0.2)
				)
				(gr_line
					(start 1.279127 1.083663)
					(end 1.279127 0.250195)
					(width 0.2)
				)
				(gr_line
					(start -1.083663 -1.279127)
					(end -0.250195 -1.279127)
					(width 0.2)
				)
			)
		)
		(pad "1" thru_hole circle
			(at 0 0 180)
			(size 6 6)
			(drill 3.7)
			(layers "*.Cu" "*.Mask")
			(remove_unused_layers no)
			(net 1 "GND")
			(pintype "passive")
		)
	)
	(footprint "antmicro-footprints:C_0402_1005Metric"
		(layer "B.Cu")
		(at 51.9 116.8 -90)
		(descr "Capacitor SMD 0402")
		(tags "capacitor SMD 0402")
		(property "Reference" "C145"
			(at 0.7 1.2 90)
			(layer "B.SilkS")
			(effects
				(font
					(size 0.7 0.7)
					(thickness 0.15)
				)
				(justify left bottom mirror)
			)
		)
		(property "Value" "C_47p_0402"
			(at 0 -1.4 90)
			(layer "B.Fab")
			(effects
				(font
					(size 0.7 0.7)
					(thickness 0.15)
				)
				(justify left bottom mirror)
			)
		)
		(property "Footprint" "antmicro-footprints:C_0402_1005Metric"
			(at 0 0 -90)
			(layer "F.Fab")
			(hide yes)
			(effects
				(font
					(size 1.27 1.27)
					(thickness 0.15)
				)
			)
		)
		(property "Datasheet" "https://www.kemet.com/en/us/capacitors/product/C0402C470J5GACTU.html"
			(at 0 0 -90)
			(layer "F.Fab")
			(hide yes)
			(effects
				(font
					(size 1.27 1.27)
					(thickness 0.15)
				)
			)
		)
		(property "Author" "Antmicro"
			(at -64.9 168.7 0)
			(layer "B.Fab")
			(hide yes)
			(effects
				(font
					(size 1 1)
					(thickness 0.15)
				)
				(justify mirror)
			)
		)
		(property "Dielectric" "C0G"
			(at -64.9 168.7 0)
			(layer "B.Fab")
			(hide yes)
			(effects
				(font
					(size 1 1)
					(thickness 0.15)
				)
				(justify mirror)
			)
		)
		(property "License" "Apache-2.0"
			(at -64.9 168.7 0)
			(layer "B.Fab")
			(hide yes)
			(effects
				(font
					(size 1 1)
					(thickness 0.15)
				)
				(justify mirror)
			)
		)
		(property "MPN" "C0402C470J5GACTU"
			(at -64.9 168.7 0)
			(layer "B.Fab")
			(hide yes)
			(effects
				(font
					(size 1 1)
					(thickness 0.15)
				)
				(justify mirror)
			)
		)
		(property "Manufacturer" "KEMET"
			(at -64.9 168.7 0)
			(layer "B.Fab")
			(hide yes)
			(effects
				(font
					(size 1 1)
					(thickness 0.15)
				)
				(justify mirror)
			)
		)
		(property "Val" "47p"
			(at -64.9 168.7 0)
			(layer "B.Fab")
			(hide yes)
			(effects
				(font
					(size 1 1)
					(thickness 0.15)
				)
				(justify mirror)
			)
		)
		(property "Voltage" ""
			(at -64.9 168.7 0)
			(layer "B.Fab")
			(hide yes)
			(effects
				(font
					(size 1 1)
					(thickness 0.15)
				)
				(justify mirror)
			)
		)
		(sheetname "USB Debug, DP")
		(sheetfile "usb.kicad_sch")
		(attr smd)
		(fp_rect
			(start -0.925 0.47)
			(end 0.925 -0.47)
			(stroke
				(width 0.05)
				(type default)
			)
			(fill none)
			(layer "B.CrtYd")
		)
		(fp_line
			(start -0.494 0.25)
			(end -0.494 -0.248)
			(stroke
				(width 0.15)
				(type solid)
			)
			(layer "B.Fab")
		)
		(fp_line
			(start 0.504 0.25)
			(end -0.494 0.25)
			(stroke
				(width 0.15)
				(type solid)
			)
			(layer "B.Fab")
		)
		(fp_line
			(start -0.494 -0.248)
			(end 0.504 -0.248)
			(stroke
				(width 0.15)
				(type solid)
			)
			(layer "B.Fab")
		)
		(fp_line
			(start 0.504 -0.248)
			(end 0.504 0.25)
			(stroke
				(width 0.15)
				(type solid)
			)
			(layer "B.Fab")
		)
		(fp_text user "License: Apache-2.0"
			(at -0.932 -5.17 90)
			(layer "B.Fab")
			(hide yes)
			(effects
				(font
					(size 0.7 0.7)
					(thickness 0.15)
				)
				(justify left bottom mirror)
			)
		)
		(fp_text user "${REFERENCE}"
			(at -0.932 -3.168 90)
			(layer "B.Fab")
			(hide yes)
			(effects
				(font
					(size 0.7 0.7)
					(thickness 0.15)
				)
				(justify left bottom mirror)
			)
		)
		(fp_text user "Author: Antmicro"
			(at -0.932 -4.17 90)
			(layer "B.Fab")
			(hide yes)
			(effects
				(font
					(size 0.7 0.7)
					(thickness 0.15)
				)
				(justify left bottom mirror)
			)
		)
		(pad "1" smd roundrect
			(at -0.48 0 270)
			(size 0.59 0.64)
			(layers "B.Cu" "B.Paste" "B.Mask")
			(roundrect_rratio 0.25)
			(net 1 "GND")
			(pintype "passive")
		)
		(pad "2" smd roundrect
			(at 0.48 0 270)
			(size 0.59 0.64)
			(layers "B.Cu" "B.Paste" "B.Mask")
			(roundrect_rratio 0.25)
			(net 275 "/USB Debug, DP/USBC3_D_N")
			(pintype "passive")
		)
	)
)
